FILE_TYPE = CONNECTIVITY;
{Allegro Design Entry HDL 17.2-2016 S081 (4005846) 1/11/2022}
"PAGE_NUMBER" = 70;
0"NC";
1"PVDD_33_S5\g";
2"GND\g";
3"PVDD18_S5_P0\g";
4"GND\g";
5"PVDD18_S5_P0\g";
6"GND\g";
%"Q_CAP"
"1","(-8600,3100)","0","pure_quanta","I1";
;
LOCATION"C2514"
$SEC"1"
CDS_SEC"1"
MATERIAL"X6S"
TOLERANCE"20%"
VALUE"22UF"
PART_NUMBER"CH622KMEB02"
VOLTAGE"4V"
PACK_TYPE"C0402"
CDS_LIB"pure_quanta";
"B"
$PN"2"6;
"A"
$PN"1"5;
%"Q_CAP"
"1","(-7700,3875)","0","pure_quanta","I10";
;
LOCATION"C2518"
$SEC"1"
CDS_SEC"1"
MATERIAL"X6S"
TOLERANCE"20%"
VALUE"22UF"
PART_NUMBER"CH622KMEB02"
VOLTAGE"4V"
PACK_TYPE"C0402"
CDS_LIB"pure_quanta";
"B"
$PN"2"4;
"A"
$PN"1"3;
%"Q_CAP"
"1","(-7250,3875)","0","pure_quanta","I11";
;
LOCATION"C2520"
$SEC"1"
CDS_SEC"1"
MATERIAL"X6S"
TOLERANCE"20%"
VALUE"22UF"
PART_NUMBER"CH622KMEB02"
VOLTAGE"4V"
PACK_TYPE"C0402"
CDS_LIB"pure_quanta";
"B"
$PN"2"4;
"A"
$PN"1"3;
%"Q_CAP"
"1","(-6800,3875)","0","pure_quanta","I12";
;
LOCATION"C2521"
$SEC"1"
CDS_SEC"1"
MATERIAL"X6S"
TOLERANCE"20%"
VALUE"22UF"
PART_NUMBER"CH622KMEB02"
VOLTAGE"4V"
PACK_TYPE"C0402"
CDS_LIB"pure_quanta";
"B"
$PN"2"4;
"A"
$PN"1"3;
%"Q_CAP"
"1","(-6350,3875)","0","pure_quanta","I13";
;
LOCATION"C2522"
$SEC"1"
CDS_SEC"1"
MATERIAL"X6S"
TOLERANCE"20%"
VALUE"22UF"
PART_NUMBER"CH622KMEB02"
VOLTAGE"4V"
PACK_TYPE"C0402"
CDS_LIB"pure_quanta";
"B"
$PN"2"4;
"A"
$PN"1"3;
%"Q_CAP"
"1","(-5900,3875)","0","pure_quanta","I14";
;
LOCATION"C2523"
$SEC"1"
CDS_SEC"1"
MATERIAL"X6S"
TOLERANCE"20%"
VALUE"22UF"
PART_NUMBER"CH622KMEB02"
VOLTAGE"4V"
PACK_TYPE"C0402"
CDS_LIB"pure_quanta";
"B"
$PN"2"4;
"A"
$PN"1"3;
%"Q_CAP"
"1","(-5450,3875)","0","pure_quanta","I15";
;
LOCATION"C2524"
$SEC"1"
CDS_SEC"1"
MATERIAL"X6S"
TOLERANCE"20%"
VALUE"22UF"
PART_NUMBER"CH622KMEB02"
VOLTAGE"4V"
PACK_TYPE"C0402"
CDS_LIB"pure_quanta";
"B"
$PN"2"4;
"A"
$PN"1"3;
%"Q_CAP"
"1","(-5000,3875)","0","pure_quanta","I16";
;
LOCATION"C2525"
$SEC"1"
CDS_SEC"1"
MATERIAL"X6S"
TOLERANCE"20%"
VALUE"22UF"
PART_NUMBER"CH622KMEB02"
VOLTAGE"4V"
PACK_TYPE"C0402"
CDS_LIB"pure_quanta";
"B"
$PN"2"4;
"A"
$PN"1"3;
%"UNIVERSAL_GND"
"1","(-4600,3500)","0","pure_quanta_power","I17";
;
CDS_LIB"pure_quanta_power"
HDL_POWER"GND";
"A"4;
%"Q_CAP"
"1","(-4600,3875)","0","pure_quanta","I18";
;
LOCATION"C2526"
$SEC"1"
CDS_SEC"1"
MATERIAL"X6S"
TOLERANCE"20%"
VALUE"22UF"
PART_NUMBER"CH622KMEB02"
VOLTAGE"4V"
PACK_TYPE"C0402"
CDS_LIB"pure_quanta";
"B"
$PN"2"4;
"A"
$PN"1"3;
%"UNIVERSAL_GND"
"1","(-8150,5125)","0","pure_quanta_power","I19";
;
CDS_LIB"pure_quanta_power"
HDL_POWER"GND";
"A"2;
%"UNIVERSAL_POWER"
"1","(-8600,3375)","0","pure_quanta_power","I2";
;
HDL_POWER"PVDD18_S5_P0"
CDS_LIB"pure_quanta_power";
"A"5;
%"Q_CAP"
"1","(-8150,5500)","0","pure_quanta","I20";
;
LOCATION"C2515"
$SEC"1"
CDS_SEC"1"
MATERIAL"X6S"
TOLERANCE"20%"
VALUE"22UF"
PART_NUMBER"CH622KMEB02"
VOLTAGE"4V"
PACK_TYPE"C0402"
CDS_LIB"pure_quanta";
"B"
$PN"2"2;
"A"
$PN"1"1;
%"Q_CAP"
"1","(-8600,3875)","0","pure_quanta","I3";
;
LOCATION"C2513"
$SEC"1"
CDS_SEC"1"
MATERIAL"X6S"
TOLERANCE"20%"
VALUE"22UF"
PART_NUMBER"CH622KMEB02"
VOLTAGE"4V"
PACK_TYPE"C0402"
CDS_LIB"pure_quanta";
"B"
$PN"2"4;
"A"
$PN"1"3;
%"UNIVERSAL_POWER"
"1","(-8600,4150)","0","pure_quanta_power","I4";
;
HDL_POWER"PVDD18_S5_P0"
CDS_LIB"pure_quanta_power";
"A"3;
%"Q_CAP"
"1","(-8600,5500)","0","pure_quanta","I5";
;
LOCATION"C2512"
$SEC"1"
CDS_SEC"1"
MATERIAL"X6S"
TOLERANCE"20%"
VALUE"22UF"
PART_NUMBER"CH622KMEB02"
VOLTAGE"4V"
PACK_TYPE"C0402"
CDS_LIB"pure_quanta";
"B"
$PN"2"2;
"A"
$PN"1"1;
%"UNIVERSAL_POWER"
"1","(-8600,5775)","0","pure_quanta_power","I6";
;
HDL_POWER"PVDD_33_S5"
CDS_LIB"pure_quanta_power";
"A"1;
%"UNIVERSAL_GND"
"1","(-8150,2750)","0","pure_quanta_power","I7";
;
CDS_LIB"pure_quanta_power"
HDL_POWER"GND";
"A"6;
%"Q_CAP"
"1","(-8150,3100)","0","pure_quanta","I8";
;
LOCATION"C2517"
$SEC"1"
CDS_SEC"1"
MATERIAL"X6S"
TOLERANCE"20%"
VALUE"22UF"
PART_NUMBER"CH622KMEB02"
VOLTAGE"4V"
PACK_TYPE"C0402"
CDS_LIB"pure_quanta";
"B"
$PN"2"6;
"A"
$PN"1"5;
%"Q_CAP"
"1","(-8150,3875)","0","pure_quanta","I9";
;
LOCATION"C2516"
$SEC"1"
CDS_SEC"1"
MATERIAL"X6S"
TOLERANCE"20%"
VALUE"22UF"
PART_NUMBER"CH622KMEB02"
VOLTAGE"4V"
PACK_TYPE"C0402"
CDS_LIB"pure_quanta";
"B"
$PN"2"4;
"A"
$PN"1"3;
END.
